# T6G (Grand Teton) — schematic netlist excerpt (pin names and nets, part order shuffled) for the footprints in the layout excerpt that follows; sources: Cadence DE-HDL packaged netlist, KiCad conversion of 04192023_DAF0TMB3IC0_F0TG_MB_C_brd_V02_OCP.brd

PL45  Q_INDUCTOR4P_14  150NH IND  pkg L_TLM117513Q-151QL_11X7-5XA  page 220
  \1\  = SW_PVDDCR_CPU1_P1_SW5
  \2\  = IND_CPU1_P1_CPL6
  \3\  = IND_CPU1_P1_CPL5
  \4\  = PVDDCR_CPU1_P1

PC6576  Q_CAP  100NF 50V 10% X7R  pkg C0402  page 363 : A = PV09_RETIMER_CPU0_VCCS ; B = GND

(kicad_pcb
	(version 20260206)
	(generator "pcbnew")
	(generator_version "10.0")
	(general
		(thickness 1.6)
		(legacy_teardrops no)
	)
	(paper "A4")
	(title_block
		(title "04192023_DAF0TMB3IC0_F0TG_MB_C_brd_V02_OCP.brd")
		(comment 1 "Grand Teton / footprints 1525-1526 of 8354")
	)
	(layers
		(0 "F.Cu" signal "TOP")
		(4 "In1.Cu" signal "GND")
		(6 "In2.Cu" signal "IN1")
		(8 "In3.Cu" signal "GND1")
		(10 "In4.Cu" signal "IN2")
		(12 "In5.Cu" signal "GND2")
		(14 "In6.Cu" signal "IN3")
		(16 "In7.Cu" signal "GND3")
		(18 "In8.Cu" signal "VCC")
		(20 "In9.Cu" signal "VCC1")
		(22 "In10.Cu" signal "GND4")
		(24 "In11.Cu" signal "IN4")
		(26 "In12.Cu" signal "GND5")
		(28 "In13.Cu" signal "IN5")
		(30 "In14.Cu" signal "GND6")
		(32 "In15.Cu" signal "IN6")
		(34 "In16.Cu" signal "GND7")
		(2 "B.Cu" signal "BOTTOM")
		(9 "F.Adhes" user "F.Adhesive")
		(11 "B.Adhes" user "B.Adhesive")
		(13 "F.Paste" user "Package Geometry/Pastemask Top")
		(15 "B.Paste" user "Package Geometry/Pastemask Bottom")
		(5 "F.SilkS" user "Ref Des/Silkscreen Top")
		(7 "B.SilkS" user "Ref Des/Silkscreen Bottom")
		(1 "F.Mask" user "Board Geometry/Soldermask Top")
		(3 "B.Mask" user "Board Geometry/Soldermask Bottom")
		(17 "Dwgs.User" user "User.Drawings")
		(19 "Cmts.User" user "User.Comments")
		(21 "Eco1.User" user "User.Eco1")
		(23 "Eco2.User" user "User.Eco2")
		(25 "Edge.Cuts" user "Board Geometry/Outline")
		(27 "Margin" user)
		(31 "F.CrtYd" user "Package Geometry/Place Bound Top")
		(29 "B.CrtYd" user "Package Geometry/Place Bound Bottom")
		(35 "F.Fab" user "Ref Des/Assembly Top")
		(33 "B.Fab" user "Ref Des/Assembly Bottom")
	)
	(footprint ""
		(layer "F.Cu")
		(at 95.494094 -325.675752)
		(property "Reference" "PL45"
			(at -2.657094 -16.689578 0)
			(unlocked yes)
			(layer "F.SilkS")
			(effects
				(font
					(size 0.7874 0.5842)
					(thickness 0.1524)
				)
				(justify left)
			)
		)
		(property "Value" ""
			(at 0 0 0)
			(layer "F.Fab")
			(effects
				(font
					(size 1.27 1.27)
				)
			)
		)
		(duplicate_pad_numbers_are_jumpers no)
		(fp_line
			(start -3.750056 -5.500116)
			(end -2.393442 -5.500116)
			(stroke
				(width 0.1524)
				(type default)
			)
			(layer "F.SilkS")
		)
		(fp_line
			(start -3.750056 5.500116)
			(end -3.750056 -5.500116)
			(stroke
				(width 0.1524)
				(type default)
			)
			(layer "F.SilkS")
		)
		(fp_line
			(start -2.393442 5.500116)
			(end -3.750056 5.500116)
			(stroke
				(width 0.1524)
				(type default)
			)
			(layer "F.SilkS")
		)
		(fp_line
			(start 2.393442 5.500116)
			(end 3.750056 5.500116)
			(stroke
				(width 0.1524)
				(type default)
			)
			(layer "F.SilkS")
		)
		(fp_line
			(start 3.750056 -5.500116)
			(end 2.393442 -5.500116)
			(stroke
				(width 0.1524)
				(type default)
			)
			(layer "F.SilkS")
		)
		(fp_line
			(start 3.750056 5.500116)
			(end 3.750056 -5.500116)
			(stroke
				(width 0.1524)
				(type default)
			)
			(layer "F.SilkS")
		)
		(fp_poly
			(pts
				(xy -3.9116 -4.249928) (xy -4.3434 -4.034028) (xy -4.3434 -4.465828)
			)
			(stroke
				(width 0)
				(type default)
			)
			(fill yes)
			(layer "F.SilkS")
		)
		(fp_line
			(start -3.750056 -5.500116)
			(end -3.750056 5.500116)
			(stroke
				(width 0.1)
				(type default)
			)
			(layer "F.Fab")
		)
		(fp_line
			(start -3.750056 5.500116)
			(end 3.750056 5.500116)
			(stroke
				(width 0.1)
				(type default)
			)
			(layer "F.Fab")
		)
		(fp_line
			(start 3.750056 -5.500116)
			(end -3.750056 -5.500116)
			(stroke
				(width 0.1)
				(type default)
			)
			(layer "F.Fab")
		)
		(fp_line
			(start 3.750056 5.500116)
			(end 3.750056 -5.500116)
			(stroke
				(width 0.1)
				(type default)
			)
			(layer "F.Fab")
		)
		(fp_poly
			(pts
				(xy -4.9276 -4.757928) (xy -4.9276 -3.741928) (xy -3.9116 -4.249928)
			)
			(stroke
				(width 0)
				(type default)
			)
			(fill yes)
			(layer "F.Fab")
		)
		(pad "1" smd rect
			(at 0 -4.249928 270)
			(size 2.413 4.5212)
			(layers "F.Cu" "F.Mask" "F.Paste")
			(net "SW_PVDDCR_CPU1_P1_SW5")
		)
		(pad "2" smd rect
			(at 0 -1.175004 270)
			(size 1.3716 4.5212)
			(layers "F.Cu" "F.Mask" "F.Paste")
			(net "IND_CPU1_P1_CPL6")
		)
		(pad "3" smd rect
			(at 0 1.175004 270)
			(size 1.3716 4.5212)
			(layers "F.Cu" "F.Mask" "F.Paste")
			(net "IND_CPU1_P1_CPL5")
		)
		(pad "4" smd rect
			(at 0 4.249928 270)
			(size 2.413 4.5212)
			(layers "F.Cu" "F.Mask" "F.Paste")
			(net "PVDDCR_CPU1_P1")
		)
	)
	(footprint ""
		(layer "F.Cu")
		(at 450.717666 -401.93087 180)
		(property "Reference" "PC6576"
			(at 0 0 180)
			(layer "F.SilkS")
			(hide yes)
			(effects
				(font
					(size 1.27 1.27)
				)
			)
		)
		(property "Value" ""
			(at 0 0 180)
			(layer "F.Fab")
			(effects
				(font
					(size 1.27 1.27)
				)
			)
		)
		(duplicate_pad_numbers_are_jumpers no)
		(fp_line
			(start 0.7874 0.4064)
			(end -0.7874 0.4064)
			(stroke
				(width 0.1524)
				(type default)
			)
			(layer "F.SilkS")
		)
		(fp_line
			(start 0.7874 -0.4064)
			(end 0.7874 0.4064)
			(stroke
				(width 0.1524)
				(type default)
			)
			(layer "F.SilkS")
		)
		(fp_line
			(start -0.7874 0.4064)
			(end -0.7874 -0.4064)
			(stroke
				(width 0.1524)
				(type default)
			)
			(layer "F.SilkS")
		)
		(fp_line
			(start -0.7874 -0.4064)
			(end 0.7874 -0.4064)
			(stroke
				(width 0.1524)
				(type default)
			)
			(layer "F.SilkS")
		)
		(fp_line
			(start 0.67945 0.3048)
			(end 0.120396 0.3048)
			(stroke
				(width 0.1)
				(type default)
			)
			(layer "F.Fab")
		)
		(fp_line
			(start 0.67945 -0.3048)
			(end 0.67945 0.3048)
			(stroke
				(width 0.1)
				(type default)
			)
			(layer "F.Fab")
		)
		(fp_line
			(start 0.12065 -0.2794)
			(end 0.12065 -0.3048)
			(stroke
				(width 0.1)
				(type default)
			)
			(layer "F.Fab")
		)
		(fp_line
			(start 0.12065 -0.3048)
			(end 0.67945 -0.3048)
			(stroke
				(width 0.1)
				(type default)
			)
			(layer "F.Fab")
		)
		(fp_line
			(start 0.120396 0.3048)
			(end 0.120396 0.2794)
			(stroke
				(width 0.1)
				(type default)
			)
			(layer "F.Fab")
		)
		(fp_line
			(start 0.120396 0.2794)
			(end -0.12065 0.2794)
			(stroke
				(width 0.1)
				(type default)
			)
			(layer "F.Fab")
		)
		(fp_line
			(start -0.12065 0.3048)
			(end -0.67945 0.3048)
			(stroke
				(width 0.1)
				(type default)
			)
			(layer "F.Fab")
		)
		(fp_line
			(start -0.12065 0.2794)
			(end -0.12065 0.3048)
			(stroke
				(width 0.1)
				(type default)
			)
			(layer "F.Fab")
		)
		(fp_line
			(start -0.12065 -0.2794)
			(end 0.12065 -0.2794)
			(stroke
				(width 0.1)
				(type default)
			)
			(layer "F.Fab")
		)
		(fp_line
			(start -0.12065 -0.305054)
			(end -0.12065 -0.2794)
			(stroke
				(width 0.1)
				(type default)
			)
			(layer "F.Fab")
		)
		(fp_line
			(start -0.67945 0.3048)
			(end -0.67945 -0.305054)
			(stroke
				(width 0.1)
				(type default)
			)
			(layer "F.Fab")
		)
		(fp_line
			(start -0.67945 -0.305054)
			(end -0.12065 -0.305054)
			(stroke
				(width 0.1)
				(type default)
			)
			(layer "F.Fab")
		)
		(pad "1" smd circle
			(at -0.40005 0 180)
			(size 0 0)
			(layers "F.Cu" "F.Mask" "F.Paste")
			(net "PV09_RETIMER_CPU0_VCCS")
		)
		(pad "2" smd circle
			(at 0.40005 0 180)
			(size 0 0)
			(layers "F.Cu" "F.Mask" "F.Paste")
			(net "GND")
		)
	)
)
